(kicad_pcb
	(version 20260206)
	(generator "pcbnew")
	(generator_version "10.0")
	(general
		(thickness 1.6)
		(legacy_teardrops no)
	)
	(paper "A4")
	(title_block
		(title "Bryce Canyon_IOM_IOC_16318-2_OCP.brd")
		(comment 1 "Bryce Canyon / footprints 188-195 of 1605")
	)
	(layers
		(0 "F.Cu" signal "TOP")
		(4 "In1.Cu" signal "L2GND")
		(6 "In2.Cu" signal "L3")
		(8 "In3.Cu" signal "L4VCC")
		(10 "In4.Cu" signal "L5VCC")
		(12 "In5.Cu" signal "L6")
		(14 "In6.Cu" signal "L7GND")
		(2 "B.Cu" signal "BOTTOM")
		(9 "F.Adhes" user "F.Adhesive")
		(11 "B.Adhes" user "B.Adhesive")
		(13 "F.Paste" user "Package Geometry/Pastemask Top")
		(15 "B.Paste" user "Package Geometry/Pastemask Bottom")
		(5 "F.SilkS" user "Ref Des/Silkscreen Top")
		(7 "B.SilkS" user "Ref Des/Silkscreen Bottom")
		(1 "F.Mask" user "Board Geometry/Soldermask Top")
		(3 "B.Mask" user "Board Geometry/Soldermask Bottom")
		(17 "Dwgs.User" user "User.Drawings")
		(19 "Cmts.User" user "User.Comments")
		(21 "Eco1.User" user "User.Eco1")
		(23 "Eco2.User" user "User.Eco2")
		(25 "Edge.Cuts" user "Board Geometry/Outline")
		(27 "Margin" user)
		(31 "F.CrtYd" user "Package Geometry/Place Bound Top")
		(29 "B.CrtYd" user "Package Geometry/Place Bound Bottom")
		(35 "F.Fab" user "Ref Des/Assembly Top")
		(33 "B.Fab" user "Ref Des/Assembly Bottom")
	)
	(footprint ""
		(layer "F.Cu")
		(at 149.827742 -97.335594 180)
		(property "Reference" "Q17"
			(at 0 0 180)
			(layer "F.SilkS")
			(hide yes)
			(effects
				(font
					(size 1.27 1.27)
				)
			)
		)
		(property "Value" "2N7002K-1-GP"
			(at 0.127 -8.9662 180)
			(unlocked yes)
			(layer "F.Fab")
			(hide yes)
			(effects
				(font
					(size 1.016 1.016)
					(thickness 0.1524)
				)
			)
		)
		(property "Device Type" "SOT23DGS2D4H44"
			(at 0.127 -10.4902 180)
			(unlocked yes)
			(layer "F.Fab")
			(hide yes)
			(effects
				(font
					(size 1.016 1.016)
					(thickness 0.1524)
				)
			)
		)
		(duplicate_pad_numbers_are_jumpers no)
		(fp_line
			(start 1.651 1.778)
			(end 1.651 -1.778)
			(stroke
				(width 0.1524)
				(type default)
			)
			(layer "F.SilkS")
		)
		(fp_line
			(start 1.651 -1.778)
			(end -1.651 -1.778)
			(stroke
				(width 0.1524)
				(type default)
			)
			(layer "F.SilkS")
		)
		(fp_line
			(start -1.651 1.778)
			(end 1.651 1.778)
			(stroke
				(width 0.1524)
				(type default)
			)
			(layer "F.SilkS")
		)
		(fp_line
			(start -1.651 -1.778)
			(end -1.651 1.778)
			(stroke
				(width 0.1524)
				(type default)
			)
			(layer "F.SilkS")
		)
		(fp_poly
			(pts
				(xy -1.778 1.8796) (xy -1.778 -1.8796) (xy 1.778 -1.8796) (xy 1.778 1.8796)
			)
			(stroke
				(width 0)
				(type default)
			)
			(fill no)
			(layer "F.CrtYd")
		)
		(fp_poly
			(pts
				(xy -1.778 1.8796) (xy -1.778 -1.8796) (xy 1.778 -1.8796) (xy 1.778 1.8796)
			)
			(stroke
				(width 0)
				(type default)
			)
			(fill no)
			(layer "F.Fab")
		)
		(pad "D" smd custom
			(at 0 -0.9525 180)
			(size 0.1905 0.1905)
			(layers "F.Cu" "F.Mask" "F.Paste")
			(net "P3V3_STBY_G")
			(options
				(clearance outline)
				(anchor circle)
			)
			(primitives
				(gr_poly
					(pts
						(arc
							(start -0.1778 0.5715)
							(mid -0.321484 0.511984)
							(end -0.381 0.3683)
						)
						(arc
							(start -0.381 -0.3683)
							(mid -0.321484 -0.511984)
							(end -0.1778 -0.5715)
						)
						(arc
							(start 0.1778 -0.5715)
							(mid 0.321484 -0.511984)
							(end 0.381 -0.3683)
						)
						(arc
							(start 0.381 0.3683)
							(mid 0.321484 0.511984)
							(end 0.1778 0.5715)
						)
					)
					(width 0)
					(fill yes)
				)
			)
		)
		(pad "G" smd custom
			(at -0.98425 0.9525 180)
			(size 0.1905 0.1905)
			(layers "F.Cu" "F.Mask" "F.Paste")
			(net "PCIE_COMP_TO_IOM_RST_2")
			(options
				(clearance outline)
				(anchor circle)
			)
			(primitives
				(gr_poly
					(pts
						(arc
							(start -0.1778 0.5715)
							(mid -0.321484 0.511984)
							(end -0.381 0.3683)
						)
						(arc
							(start -0.381 -0.3683)
							(mid -0.321484 -0.511984)
							(end -0.1778 -0.5715)
						)
						(arc
							(start 0.1778 -0.5715)
							(mid 0.321484 -0.511984)
							(end 0.381 -0.3683)
						)
						(arc
							(start 0.381 0.3683)
							(mid 0.321484 0.511984)
							(end 0.1778 0.5715)
						)
					)
					(width 0)
					(fill yes)
				)
			)
		)
		(pad "S" smd custom
			(at 0.98425 0.9525 180)
			(size 0.1905 0.1905)
			(layers "F.Cu" "F.Mask" "F.Paste")
			(net "GND")
			(options
				(clearance outline)
				(anchor circle)
			)
			(primitives
				(gr_poly
					(pts
						(arc
							(start -0.1778 0.5715)
							(mid -0.321484 0.511984)
							(end -0.381 0.3683)
						)
						(arc
							(start -0.381 -0.3683)
							(mid -0.321484 -0.511984)
							(end -0.1778 -0.5715)
						)
						(arc
							(start 0.1778 -0.5715)
							(mid 0.321484 -0.511984)
							(end 0.381 -0.3683)
						)
						(arc
							(start 0.381 0.3683)
							(mid 0.321484 0.511984)
							(end 0.1778 0.5715)
						)
					)
					(width 0)
					(fill yes)
				)
			)
		)
	)
	(footprint ""
		(layer "F.Cu")
		(at 190.220346 -133.265164)
		(property "Reference" "R558"
			(at 0 0 0)
			(layer "F.SilkS")
			(hide yes)
			(effects
				(font
					(size 1.27 1.27)
				)
			)
		)
		(property "Value" "0R2J-2-GP"
			(at 0.064008 -3.993896 0)
			(unlocked yes)
			(layer "F.Fab")
			(hide yes)
			(effects
				(font
					(size 1.016 1.016)
					(thickness 0.1524)
				)
			)
		)
		(property "Device Type" "R402H16"
			(at 0.064008 -5.517896 0)
			(unlocked yes)
			(layer "F.Fab")
			(hide yes)
			(effects
				(font
					(size 1.016 1.016)
					(thickness 0.1524)
				)
			)
		)
		(duplicate_pad_numbers_are_jumpers no)
		(fp_line
			(start -0.508 -0.9398)
			(end -0.508 0.9398)
			(stroke
				(width 0.1524)
				(type default)
			)
			(layer "F.SilkS")
		)
		(fp_line
			(start 0.508 -0.9398)
			(end -0.508 -0.9398)
			(stroke
				(width 0.1524)
				(type default)
			)
			(layer "F.SilkS")
		)
		(fp_rect
			(start -0.508 0.9398)
			(end 0.508 -0.9398)
			(stroke
				(width 0)
				(type default)
			)
			(fill no)
			(layer "F.CrtYd")
		)
		(fp_rect
			(start -0.508 0.9398)
			(end 0.508 -0.9398)
			(stroke
				(width 0)
				(type default)
			)
			(fill no)
			(layer "F.Fab")
		)
		(pad "1" smd custom
			(at 0 -0.4445)
			(size 0.1397 0.1397)
			(layers "F.Cu" "F.Mask" "F.Paste")
			(net "PWRGD_P1V5")
			(options
				(clearance outline)
				(anchor circle)
			)
			(primitives
				(gr_poly
					(pts
						(arc
							(start -0.1778 -0.2794)
							(mid -0.249642 -0.249642)
							(end -0.2794 -0.1778)
						)
						(arc
							(start -0.2794 0.1778)
							(mid -0.249642 0.249642)
							(end -0.1778 0.2794)
						)
						(arc
							(start 0.1778 0.2794)
							(mid 0.249642 0.249642)
							(end 0.2794 0.1778)
						)
						(arc
							(start 0.2794 -0.1778)
							(mid 0.249642 -0.249642)
							(end 0.1778 -0.2794)
						)
					)
					(width 0)
					(fill yes)
				)
			)
		)
		(pad "2" smd custom
			(at 0 0.4445)
			(size 0.1397 0.1397)
			(layers "F.Cu" "F.Mask" "F.Paste")
			(net "VT235_EN")
			(options
				(clearance outline)
				(anchor circle)
			)
			(primitives
				(gr_poly
					(pts
						(arc
							(start -0.1778 -0.2794)
							(mid -0.249642 -0.249642)
							(end -0.2794 -0.1778)
						)
						(arc
							(start -0.2794 0.1778)
							(mid -0.249642 0.249642)
							(end -0.1778 0.2794)
						)
						(arc
							(start 0.1778 0.2794)
							(mid 0.249642 0.249642)
							(end 0.2794 0.1778)
						)
						(arc
							(start 0.2794 -0.1778)
							(mid 0.249642 -0.249642)
							(end 0.1778 -0.2794)
						)
					)
					(width 0)
					(fill yes)
				)
			)
		)
	)
	(footprint ""
		(layer "F.Cu")
		(at 66.422778 -159.068262 90)
		(property "Reference" "C518"
			(at 0 0 90)
			(layer "F.SilkS")
			(hide yes)
			(effects
				(font
					(size 1.27 1.27)
				)
			)
		)
		(property "Value" "SCD1U25V2KX-2-GP"
			(at 1.1811 -2.7051 90)
			(unlocked yes)
			(layer "F.Fab")
			(hide yes)
			(effects
				(font
					(size 1.016 1.016)
					(thickness 0.1524)
				)
			)
		)
		(property "Device Type" "C402H22"
			(at 1.1811 -4.2291 90)
			(unlocked yes)
			(layer "F.Fab")
			(hide yes)
			(effects
				(font
					(size 1.016 1.016)
					(thickness 0.1524)
				)
			)
		)
		(duplicate_pad_numbers_are_jumpers no)
		(fp_rect
			(start -0.4318 0.9525)
			(end 0.4318 -0.9525)
			(stroke
				(width 0)
				(type default)
			)
			(fill no)
			(layer "F.CrtYd")
		)
		(fp_rect
			(start -0.4318 0.9525)
			(end 0.4318 -0.9525)
			(stroke
				(width 0)
				(type default)
			)
			(fill no)
			(layer "F.Fab")
		)
		(pad "1" smd custom
			(at 0 -0.4445 90)
			(size 0.1524 0.1524)
			(layers "F.Cu" "F.Mask" "F.Paste")
			(net "ADC_P1V15_STBY")
			(options
				(clearance outline)
				(anchor circle)
			)
			(primitives
				(gr_poly
					(pts
						(arc
							(start 0.3048 -0.2032)
							(mid 0.275042 -0.275042)
							(end 0.2032 -0.3048)
						)
						(arc
							(start -0.2032 -0.3048)
							(mid -0.275042 -0.275042)
							(end -0.3048 -0.2032)
						)
						(arc
							(start -0.3048 0.2032)
							(mid -0.275042 0.275042)
							(end -0.2032 0.3048)
						)
						(arc
							(start 0.2032 0.3048)
							(mid 0.275042 0.275042)
							(end 0.3048 0.2032)
						)
					)
					(width 0)
					(fill yes)
				)
			)
		)
		(pad "2" smd custom
			(at 0 0.4445 90)
			(size 0.1524 0.1524)
			(layers "F.Cu" "F.Mask" "F.Paste")
			(net "GND")
			(options
				(clearance outline)
				(anchor circle)
			)
			(primitives
				(gr_poly
					(pts
						(arc
							(start 0.3048 -0.2032)
							(mid 0.275042 -0.275042)
							(end 0.2032 -0.3048)
						)
						(arc
							(start -0.2032 -0.3048)
							(mid -0.275042 -0.275042)
							(end -0.3048 -0.2032)
						)
						(arc
							(start -0.3048 0.2032)
							(mid -0.275042 0.275042)
							(end -0.2032 0.3048)
						)
						(arc
							(start 0.2032 0.3048)
							(mid 0.275042 0.275042)
							(end 0.3048 0.2032)
						)
					)
					(width 0)
					(fill yes)
				)
			)
		)
	)
	(footprint ""
		(layer "F.Cu")
		(at 176.1236 -38.5318)
		(property "Reference" "TP172"
			(at 0 0 0)
			(layer "F.SilkS")
			(hide yes)
			(effects
				(font
					(size 1.27 1.27)
				)
			)
		)
		(property "Value" "TPAD28-2-GP"
			(at -0.0127 -1.6637 0)
			(unlocked yes)
			(layer "F.Fab")
			(hide yes)
			(effects
				(font
					(size 1.016 1.016)
					(thickness 0.1524)
				)
			)
		)
		(property "Device Type" "TPAD28"
			(at -0.0127 -3.1877 0)
			(unlocked yes)
			(layer "F.Fab")
			(hide yes)
			(effects
				(font
					(size 1.016 1.016)
					(thickness 0.1524)
				)
			)
		)
		(duplicate_pad_numbers_are_jumpers no)
		(fp_poly
			(pts
				(arc
					(start 0.3556 0)
					(mid -0.3556 0)
					(end 0.3556 0)
				)
			)
			(stroke
				(width 0)
				(type default)
			)
			(fill no)
			(layer "F.CrtYd")
		)
		(fp_poly
			(pts
				(arc
					(start 0.6096 0)
					(mid -0.6096 0)
					(end 0.6096 0)
				)
			)
			(stroke
				(width 0)
				(type default)
			)
			(fill no)
			(layer "F.Fab")
		)
		(pad "1" smd circle
			(at 0 0)
			(size 0.7112 0.7112)
			(layers "F.Cu" "F.Mask" "F.Paste")
			(net "ZDEF_EXTA_TP_C2")
		)
	)
	(footprint ""
		(layer "F.Cu")
		(at 208.055972 -67.7672 90)
		(property "Reference" "C318"
			(at 0 0 90)
			(layer "F.SilkS")
			(hide yes)
			(effects
				(font
					(size 1.27 1.27)
				)
			)
		)
		(property "Value" "SCD01U16V1KX-GP"
			(at -2.8321 -1.7399 90)
			(unlocked yes)
			(layer "F.Fab")
			(hide yes)
			(effects
				(font
					(size 1.016 1.016)
					(thickness 0.1524)
				)
			)
		)
		(property "Device Type" "C0201H13"
			(at -2.8321 -3.2639 90)
			(unlocked yes)
			(layer "F.Fab")
			(hide yes)
			(effects
				(font
					(size 1.016 1.016)
					(thickness 0.1524)
				)
			)
		)
		(duplicate_pad_numbers_are_jumpers no)
		(fp_rect
			(start -0.2794 0.6477)
			(end 0.2794 -0.6477)
			(stroke
				(width 0)
				(type default)
			)
			(fill no)
			(layer "F.CrtYd")
		)
		(fp_rect
			(start -0.2794 0.6477)
			(end 0.2794 -0.6477)
			(stroke
				(width 0)
				(type default)
			)
			(fill no)
			(layer "F.Fab")
		)
		(pad "1" smd custom
			(at 0 -0.2794 90)
			(size 0.0762 0.0762)
			(layers "F.Cu" "F.Mask" "F.Paste")
			(net "PHY_IOC_TO_CON_B_1_DN_C")
			(options
				(clearance outline)
				(anchor circle)
			)
			(primitives
				(gr_poly
					(pts
						(arc
							(start 0.1524 -0.127)
							(mid 0.137521 -0.162921)
							(end 0.1016 -0.1778)
						)
						(arc
							(start -0.1016 -0.1778)
							(mid -0.137521 -0.162921)
							(end -0.1524 -0.127)
						)
						(arc
							(start -0.1524 0.127)
							(mid -0.137521 0.162921)
							(end -0.1016 0.1778)
						)
						(arc
							(start 0.1016 0.1778)
							(mid 0.137521 0.162921)
							(end 0.1524 0.127)
						)
					)
					(width 0)
					(fill yes)
				)
			)
		)
		(pad "2" smd custom
			(at 0 0.2794 90)
			(size 0.0762 0.0762)
			(layers "F.Cu" "F.Mask" "F.Paste")
			(net "PHY_IOC_TO_CON_B_1_DN")
			(options
				(clearance outline)
				(anchor circle)
			)
			(primitives
				(gr_poly
					(pts
						(arc
							(start 0.1524 -0.127)
							(mid 0.137521 -0.162921)
							(end 0.1016 -0.1778)
						)
						(arc
							(start -0.1016 -0.1778)
							(mid -0.137521 -0.162921)
							(end -0.1524 -0.127)
						)
						(arc
							(start -0.1524 0.127)
							(mid -0.137521 0.162921)
							(end -0.1016 0.1778)
						)
						(arc
							(start 0.1016 0.1778)
							(mid 0.137521 0.162921)
							(end 0.1524 0.127)
						)
					)
					(width 0)
					(fill yes)
				)
			)
		)
	)
	(footprint ""
		(layer "F.Cu")
		(at 177.216562 -53.782722 90)
		(property "Reference" "R766"
			(at 0 0 90)
			(layer "F.SilkS")
			(hide yes)
			(effects
				(font
					(size 1.27 1.27)
				)
			)
		)
		(property "Value" "10KR2F-2-GP"
			(at 0.064008 -3.993896 90)
			(unlocked yes)
			(layer "F.Fab")
			(hide yes)
			(effects
				(font
					(size 1.016 1.016)
					(thickness 0.1524)
				)
			)
		)
		(property "Device Type" "R402H16"
			(at 0.064008 -5.517896 90)
			(unlocked yes)
			(layer "F.Fab")
			(hide yes)
			(effects
				(font
					(size 1.016 1.016)
					(thickness 0.1524)
				)
			)
		)
		(duplicate_pad_numbers_are_jumpers no)
		(fp_line
			(start 0.508 -0.9398)
			(end -0.508 -0.9398)
			(stroke
				(width 0.1524)
				(type default)
			)
			(layer "F.SilkS")
		)
		(fp_line
			(start -0.508 -0.9398)
			(end -0.508 0.9398)
			(stroke
				(width 0.1524)
				(type default)
			)
			(layer "F.SilkS")
		)
		(fp_rect
			(start -0.508 0.9398)
			(end 0.508 -0.9398)
			(stroke
				(width 0)
				(type default)
			)
			(fill no)
			(layer "F.CrtYd")
		)
		(fp_rect
			(start -0.508 0.9398)
			(end 0.508 -0.9398)
			(stroke
				(width 0)
				(type default)
			)
			(fill no)
			(layer "F.Fab")
		)
		(pad "1" smd custom
			(at 0 -0.4445 90)
			(size 0.1397 0.1397)
			(layers "F.Cu" "F.Mask" "F.Paste")
			(net "P1V8")
			(options
				(clearance outline)
				(anchor circle)
			)
			(primitives
				(gr_poly
					(pts
						(arc
							(start -0.1778 -0.2794)
							(mid -0.249642 -0.249642)
							(end -0.2794 -0.1778)
						)
						(arc
							(start -0.2794 0.1778)
							(mid -0.249642 0.249642)
							(end -0.1778 0.2794)
						)
						(arc
							(start 0.1778 0.2794)
							(mid 0.249642 0.249642)
							(end 0.2794 0.1778)
						)
						(arc
							(start 0.2794 -0.1778)
							(mid 0.249642 -0.249642)
							(end 0.1778 -0.2794)
						)
					)
					(width 0)
					(fill yes)
				)
			)
		)
		(pad "2" smd custom
			(at 0 0.4445 90)
			(size 0.1397 0.1397)
			(layers "F.Cu" "F.Mask" "F.Paste")
			(net "XM_ADDR_11")
			(options
				(clearance outline)
				(anchor circle)
			)
			(primitives
				(gr_poly
					(pts
						(arc
							(start -0.1778 -0.2794)
							(mid -0.249642 -0.249642)
							(end -0.2794 -0.1778)
						)
						(arc
							(start -0.2794 0.1778)
							(mid -0.249642 0.249642)
							(end -0.1778 0.2794)
						)
						(arc
							(start 0.1778 0.2794)
							(mid 0.249642 0.249642)
							(end 0.2794 0.1778)
						)
						(arc
							(start 0.2794 -0.1778)
							(mid 0.249642 -0.249642)
							(end 0.1778 -0.2794)
						)
					)
					(width 0)
					(fill yes)
				)
			)
		)
	)
	(footprint ""
		(layer "F.Cu")
		(at 186.817 -49.9872)
		(property "Reference" "TP168"
			(at 0 0 0)
			(layer "F.SilkS")
			(hide yes)
			(effects
				(font
					(size 1.27 1.27)
				)
			)
		)
		(property "Value" "TPAD28-2-GP"
			(at -0.0127 -1.6637 0)
			(unlocked yes)
			(layer "F.Fab")
			(hide yes)
			(effects
				(font
					(size 1.016 1.016)
					(thickness 0.1524)
				)
			)
		)
		(property "Device Type" "TPAD28"
			(at -0.0127 -3.1877 0)
			(unlocked yes)
			(layer "F.Fab")
			(hide yes)
			(effects
				(font
					(size 1.016 1.016)
					(thickness 0.1524)
				)
			)
		)
		(duplicate_pad_numbers_are_jumpers no)
		(fp_poly
			(pts
				(arc
					(start 0.3556 0)
					(mid -0.3556 0)
					(end 0.3556 0)
				)
			)
			(stroke
				(width 0)
				(type default)
			)
			(fill no)
			(layer "F.CrtYd")
		)
		(fp_poly
			(pts
				(arc
					(start 0.6096 0)
					(mid -0.6096 0)
					(end 0.6096 0)
				)
			)
			(stroke
				(width 0)
				(type default)
			)
			(fill no)
			(layer "F.Fab")
		)
		(pad "1" smd circle
			(at 0 0)
			(size 0.7112 0.7112)
			(layers "F.Cu" "F.Mask" "F.Paste")
			(net "XM_RB")
		)
	)
	(footprint ""
		(layer "F.Cu")
		(at 127.665988 -6.399022)
		(property "Reference" "C146"
			(at 0 0 0)
			(layer "F.SilkS")
			(hide yes)
			(effects
				(font
					(size 1.27 1.27)
				)
			)
		)
		(property "Value" "SCD033U50V3KX-1GP"
			(at 0 -2.8194 0)
			(unlocked yes)
			(layer "F.Fab")
			(hide yes)
			(effects
				(font
					(size 1.016 1.016)
					(thickness 0.1524)
				)
			)
		)
		(property "Device Type" "C603H36"
			(at 0 -4.3434 0)
			(unlocked yes)
			(layer "F.Fab")
			(hide yes)
			(effects
				(font
					(size 1.016 1.016)
					(thickness 0.1524)
				)
			)
		)
		(duplicate_pad_numbers_are_jumpers no)
		(fp_line
			(start 0.508 0)
			(end -0.508 0)
			(stroke
				(width 0.2032)
				(type default)
			)
			(layer "F.SilkS")
		)
		(fp_rect
			(start -0.5842 1.3335)
			(end 0.5842 -1.3335)
			(stroke
				(width 0)
				(type default)
			)
			(fill no)
			(layer "F.CrtYd")
		)
		(fp_rect
			(start -0.5842 1.3335)
			(end 0.5842 -1.3335)
			(stroke
				(width 0)
				(type default)
			)
			(fill no)
			(layer "F.Fab")
		)
		(pad "1" smd custom
			(at 0 -0.762)
			(size 0.2159 0.2159)
			(layers "F.Cu" "F.Mask" "F.Paste")
			(net "MB0_CM_GATE_2")
			(options
				(clearance outline)
				(anchor circle)
			)
			(primitives
				(gr_poly
					(pts
						(arc
							(start -0.3302 -0.4318)
							(mid -0.402042 -0.402042)
							(end -0.4318 -0.3302)
						)
						(arc
							(start -0.4318 0.3302)
							(mid -0.402042 0.402042)
							(end -0.3302 0.4318)
						)
						(arc
							(start 0.3302 0.4318)
							(mid 0.402042 0.402042)
							(end 0.4318 0.3302)
						)
						(arc
							(start 0.4318 -0.3302)
							(mid 0.402042 -0.402042)
							(end 0.3302 -0.4318)
						)
					)
					(width 0)
					(fill yes)
				)
			)
		)
		(pad "2" smd custom
			(at 0 0.762)
			(size 0.2159 0.2159)
			(layers "F.Cu" "F.Mask" "F.Paste")
			(net "GND")
			(options
				(clearance outline)
				(anchor circle)
			)
			(primitives
				(gr_poly
					(pts
						(arc
							(start -0.3302 -0.4318)
							(mid -0.402042 -0.402042)
							(end -0.4318 -0.3302)
						)
						(arc
							(start -0.4318 0.3302)
							(mid -0.402042 0.402042)
							(end -0.3302 0.4318)
						)
						(arc
							(start 0.3302 0.4318)
							(mid 0.402042 0.402042)
							(end 0.4318 0.3302)
						)
						(arc
							(start 0.4318 -0.3302)
							(mid 0.402042 -0.402042)
							(end 0.3302 -0.4318)
						)
					)
					(width 0)
					(fill yes)
				)
			)
		)
	)
)
